(kicad_pcb
	(version 20260206)
	(generator "pcbnew")
	(generator_version "10.0")
	(general
		(thickness 1.21888)
		(legacy_teardrops no)
	)
	(paper "A4")
	(title_block
		(title "timecard-v7 — TimeCard-DC-V7_EXP.PcbDoc")
		(comment 1 "Time Appliance Project (Time Card) / footprints 121-132 of 160")
	)
	(layers
		(0 "F.Cu" signal "TOP")
		(4 "In1.Cu" signal "SGND")
		(6 "In2.Cu" signal "IN1")
		(8 "In3.Cu" signal "IN2")
		(10 "In4.Cu" signal "SGND1")
		(2 "B.Cu" signal "BOTTOM")
		(9 "F.Adhes" user "F.Adhesive")
		(11 "B.Adhes" user "B.Adhesive")
		(13 "F.Paste" user "Top Paste")
		(15 "B.Paste" user "Bottom Paste")
		(5 "F.SilkS" user "Top Overlay")
		(7 "B.SilkS" user "Bottom Overlay")
		(1 "F.Mask" user "Top Solder")
		(3 "B.Mask" user "Bottom Solder")
		(17 "Dwgs.User" user "User.Drawings")
		(19 "Cmts.User" user "User.Comments")
		(21 "Eco1.User" user "User.Eco1")
		(23 "Eco2.User" user "User.Eco2")
		(25 "Edge.Cuts" user)
		(27 "Margin" user)
		(31 "F.CrtYd" user "Top Courtyard")
		(29 "B.CrtYd" user "Bottom Courtyard")
		(35 "F.Fab" user "Top Component Center")
		(33 "B.Fab" user "Bottom Component Center")
	)
	(footprint "Capacitors:CAPC2012X14N"
		(layer "F.Cu")
		(at 153.9261 80.6162 90)
		(property "Reference" "C62"
			(at 1.3 1.406655 270)
			(unlocked yes)
			(layer "F.SilkS")
			(effects
				(font
					(size 0.762 0.762)
					(thickness 0.2286)
				)
				(justify left bottom)
			)
		)
		(property "Value" "CAP_0805_10UF_25V"
			(at -2.52679 -1.7875 0)
			(unlocked yes)
			(layer "F.SilkS")
			(hide yes)
			(effects
				(font
					(size 1.524 1.524)
					(thickness 0.254)
				)
				(justify left bottom)
			)
		)
		(sheetname "MAC")
		(sheetfile "MAC.kicad_sch")
		(duplicate_pad_numbers_are_jumpers no)
		(fp_line
			(start -0.762 -0.9652)
			(end 0.762 -0.9652)
			(stroke
				(width 0.1524)
				(type solid)
			)
			(layer "F.SilkS")
		)
		(fp_line
			(start -0.762 0.9652)
			(end 0.762 0.9652)
			(stroke
				(width 0.1524)
				(type solid)
			)
			(layer "F.SilkS")
		)
		(pad "1" smd rect
			(at -0.9 0 180)
			(size 1.45 1.15)
			(layers "F.Cu" "F.Mask" "F.Paste")
			(net "MAC_VCC")
		)
		(pad "2" smd rect
			(at 0.9 0 180)
			(size 1.45 1.15)
			(layers "F.Cu" "F.Mask" "F.Paste")
			(net "GND")
		)
	)
	(footprint "Vault:CAPC1608X87X45ML20T05"
		(layer "F.Cu")
		(at 84.1261 87.1162 90)
		(property "Reference" "C40"
			(at 0.4786 -3.473069 90)
			(unlocked yes)
			(layer "F.SilkS")
			(effects
				(font
					(size 0.762 0.762)
					(thickness 0.2286)
				)
			)
		)
		(property "Value" "0.1uF"
			(at 2.09443 2.657602 90)
			(unlocked yes)
			(layer "F.SilkS")
			(hide yes)
			(effects
				(font
					(size 1.524 1.524)
					(thickness 0.254)
				)
			)
		)
		(sheetname "USER_IO_STATUS")
		(sheetfile "USER_IO_STATUS.kicad_sch")
		(duplicate_pad_numbers_are_jumpers no)
		(pad "1" smd rect
			(at -0.7 0 180)
			(size 1.1 1.05)
			(layers "F.Cu" "F.Mask" "F.Paste")
			(net "GND")
		)
		(pad "2" smd rect
			(at 0.7 0 180)
			(size 1.1 1.05)
			(layers "F.Cu" "F.Mask" "F.Paste")
			(net "+3.3V")
		)
	)
	(footprint "Vault:CAPC1608X87X45ML20T05"
		(layer "F.Cu")
		(at 151.54502 80.89267 -90)
		(property "Reference" "C63"
			(at 0.62353 1.525575 90)
			(unlocked yes)
			(layer "F.SilkS")
			(effects
				(font
					(size 0.762 0.762)
					(thickness 0.2286)
				)
				(justify left bottom)
			)
		)
		(property "Value" "0.1uF"
			(at 1.92305 -4.27006 0)
			(unlocked yes)
			(layer "F.SilkS")
			(hide yes)
			(effects
				(font
					(size 1.524 1.524)
					(thickness 0.254)
				)
				(justify left bottom)
			)
		)
		(sheetname "MAC")
		(sheetfile "MAC.kicad_sch")
		(duplicate_pad_numbers_are_jumpers no)
		(pad "1" smd rect
			(at -0.7 0)
			(size 1.1 1.05)
			(layers "F.Cu" "F.Mask" "F.Paste")
			(net "GND")
		)
		(pad "2" smd rect
			(at 0.7 0)
			(size 1.1 1.05)
			(layers "F.Cu" "F.Mask" "F.Paste")
			(net "MAC_VCC")
		)
	)
	(footprint "Resistors:RESC2012X50N"
		(layer "F.Cu")
		(at 199.41136 139.37763)
		(property "Reference" "R18"
			(at -0.68526 -1.068085 0)
			(unlocked yes)
			(layer "F.SilkS")
			(effects
				(font
					(size 0.762 0.762)
					(thickness 0.2286)
				)
				(justify left bottom)
			)
		)
		(property "Value" "CRCW080533R0FKEA"
			(at -5.5249 -8.83582 0)
			(unlocked yes)
			(layer "F.SilkS")
			(hide yes)
			(effects
				(font
					(size 1.524 1.524)
					(thickness 0.254)
				)
				(justify left bottom)
			)
		)
		(sheetname "PCIe_JTAG")
		(sheetfile "PCIe_JTAG.kicad_sch")
		(duplicate_pad_numbers_are_jumpers no)
		(fp_line
			(start 0 0.762)
			(end 0 -0.762)
			(stroke
				(width 0.1524)
				(type solid)
			)
			(layer "F.SilkS")
		)
		(pad "1" smd rect
			(at -1 0 90)
			(size 1.45 0.95)
			(layers "F.Cu" "F.Mask" "F.Paste")
			(net "FPGA_TCK")
		)
		(pad "2" smd rect
			(at 1 0 90)
			(size 1.45 0.95)
			(layers "F.Cu" "F.Mask" "F.Paste")
			(net "NetR18_2")
		)
	)
	(footprint "Vault:M08A_L"
		(layer "F.Cu")
		(at 118.6261 86.0786)
		(property "Reference" "U4"
			(at 2.128595 -3.135469 0)
			(unlocked yes)
			(layer "F.SilkS")
			(effects
				(font
					(size 0.762 0.762)
					(thickness 0.2286)
				)
			)
		)
		(property "Value" "DS90LV028AQMA"
			(at 6.74058 4.207002 0)
			(unlocked yes)
			(layer "F.SilkS")
			(hide yes)
			(effects
				(font
					(size 1.524 1.524)
					(thickness 0.254)
				)
			)
		)
		(sheetname "MAC")
		(sheetfile "MAC.kicad_sch")
		(duplicate_pad_numbers_are_jumpers no)
		(fp_line
			(start -1 -2.5)
			(end 1 -2.5)
			(stroke
				(width 0.2)
				(type solid)
			)
			(layer "F.SilkS")
		)
		(fp_line
			(start -1 2.5)
			(end -1 -2.5)
			(stroke
				(width 0.2)
				(type solid)
			)
			(layer "F.SilkS")
		)
		(fp_line
			(start -1 2.5)
			(end 1 2.5)
			(stroke
				(width 0.2)
				(type solid)
			)
			(layer "F.SilkS")
		)
		(fp_line
			(start 1 2.5)
			(end 1 -2.5)
			(stroke
				(width 0.2)
				(type solid)
			)
			(layer "F.SilkS")
		)
		(fp_circle
			(center -2.35 -2.755)
			(end -2.35 -2.88)
			(stroke
				(width 0.25)
				(type solid)
			)
			(fill no)
			(layer "F.SilkS")
		)
		(fp_circle
			(center -0.2 -1.7)
			(end -0.2 -1.9)
			(stroke
				(width 0.4)
				(type solid)
			)
			(fill no)
			(layer "F.SilkS")
		)
		(pad "1" smd oval
			(at -2.35 -1.905 90)
			(size 0.6 1.9)
			(layers "F.Cu" "F.Mask" "F.Paste")
			(net "MAC_PPS_OUT-")
		)
		(pad "2" smd oval
			(at -2.35 -0.635 90)
			(size 0.6 1.9)
			(layers "F.Cu" "F.Mask" "F.Paste")
			(net "MAC_PPS_OUT+")
		)
		(pad "3" smd oval
			(at -2.35 0.635 90)
			(size 0.6 1.9)
			(layers "F.Cu" "F.Mask" "F.Paste")
		)
		(pad "4" smd oval
			(at -2.35 1.905 90)
			(size 0.6 1.9)
			(layers "F.Cu" "F.Mask" "F.Paste")
		)
		(pad "5" smd oval
			(at 2.35 1.905 90)
			(size 0.6 1.9)
			(layers "F.Cu" "F.Mask" "F.Paste")
			(net "GND")
		)
		(pad "6" smd oval
			(at 2.35 0.635 90)
			(size 0.6 1.9)
			(layers "F.Cu" "F.Mask" "F.Paste")
		)
		(pad "7" smd oval
			(at 2.35 -0.635 90)
			(size 0.6 1.9)
			(layers "F.Cu" "F.Mask" "F.Paste")
			(net "NetR13_1")
		)
		(pad "8" smd oval
			(at 2.35 -1.905 90)
			(size 0.6 1.9)
			(layers "F.Cu" "F.Mask" "F.Paste")
			(net "+3.3V")
		)
	)
	(footprint "SA53:SA53_Header"
		(layer "F.Cu")
		(at 142.66107 112.99691 180)
		(property "Reference" "J31"
			(at 3.071485 -8.827838 180)
			(unlocked yes)
			(layer "F.SilkS")
			(effects
				(font
					(size 1.524 1.524)
					(thickness 0.254)
				)
			)
		)
		(property "Value" "SA53_Header"
			(at 7.680915 4.511792 180)
			(unlocked yes)
			(layer "F.SilkS")
			(hide yes)
			(effects
				(font
					(size 1.524 1.524)
					(thickness 0.254)
				)
			)
		)
		(sheetname "MAC")
		(sheetfile "MAC.kicad_sch")
		(duplicate_pad_numbers_are_jumpers no)
		(fp_circle
			(center 6.42 0.07199)
			(end 6.42 0.19899)
			(stroke
				(width 0.254)
				(type solid)
			)
			(fill no)
			(layer "F.SilkS")
		)
		(pad "1" smd rect
			(at 5 0.07199 270)
			(size 0.25 1.8)
			(layers "F.Cu" "F.Mask" "F.Paste")
			(net "MAC_PPS_IN1+")
		)
		(pad "2" smd rect
			(at 1 0.07199 270)
			(size 0.25 1.8)
			(layers "F.Cu" "F.Mask" "F.Paste")
			(net "MAC_USB+")
		)
		(pad "3" smd rect
			(at 5 -0.43601 270)
			(size 0.25 1.8)
			(layers "F.Cu" "F.Mask" "F.Paste")
			(net "MAC_PPS_IN1-")
		)
		(pad "4" smd rect
			(at 1 -0.43601 270)
			(size 0.25 1.8)
			(layers "F.Cu" "F.Mask" "F.Paste")
			(net "MAC_USB-")
		)
		(pad "5" smd rect
			(at 5 -0.94401 270)
			(size 0.25 1.8)
			(layers "F.Cu" "F.Mask" "F.Paste")
			(net "MAC_PPS_IN0+")
		)
		(pad "6" smd rect
			(at 1 -0.94401 270)
			(size 0.25 1.8)
			(layers "F.Cu" "F.Mask" "F.Paste")
			(net "MAC_USB_PWR")
		)
		(pad "7" smd rect
			(at 5 -1.45201 270)
			(size 0.25 1.8)
			(layers "F.Cu" "F.Mask" "F.Paste")
			(net "MAC_PPS_IN0-")
		)
		(pad "8" smd rect
			(at 1 -1.45201 270)
			(size 0.25 1.8)
			(layers "F.Cu" "F.Mask" "F.Paste")
			(net "GND")
		)
		(pad "9" smd rect
			(at 5 -1.96001 270)
			(size 0.25 1.8)
			(layers "F.Cu" "F.Mask" "F.Paste")
			(net "GND")
		)
		(pad "10" smd rect
			(at 1 -1.96001 270)
			(size 0.25 1.8)
			(layers "F.Cu" "F.Mask" "F.Paste")
		)
		(pad "11" smd rect
			(at 5 -2.46801 270)
			(size 0.25 1.8)
			(layers "F.Cu" "F.Mask" "F.Paste")
		)
		(pad "12" smd rect
			(at 1 -2.46801 270)
			(size 0.25 1.8)
			(layers "F.Cu" "F.Mask" "F.Paste")
		)
		(pad "13" smd rect
			(at 5 -2.97601 270)
			(size 0.25 1.8)
			(layers "F.Cu" "F.Mask" "F.Paste")
		)
		(pad "14" smd rect
			(at 1 -2.97601 270)
			(size 0.25 1.8)
			(layers "F.Cu" "F.Mask" "F.Paste")
		)
		(pad "15" smd rect
			(at 5 -3.48401 270)
			(size 0.25 1.8)
			(layers "F.Cu" "F.Mask" "F.Paste")
			(net "GND")
		)
		(pad "16" smd rect
			(at 1 -3.48401 270)
			(size 0.25 1.8)
			(layers "F.Cu" "F.Mask" "F.Paste")
		)
		(pad "17" smd rect
			(at 5 -3.99201 270)
			(size 0.25 1.8)
			(layers "F.Cu" "F.Mask" "F.Paste")
			(net "MAC_PPS_OUT+")
		)
		(pad "18" smd rect
			(at 1 -3.99201 270)
			(size 0.25 1.8)
			(layers "F.Cu" "F.Mask" "F.Paste")
		)
		(pad "19" smd rect
			(at 5 -4.50001 270)
			(size 0.25 1.8)
			(layers "F.Cu" "F.Mask" "F.Paste")
			(net "MAC_PPS_OUT-")
		)
		(pad "20" smd rect
			(at 1 -4.50001 270)
			(size 0.25 1.8)
			(layers "F.Cu" "F.Mask" "F.Paste")
			(net "MAC_ALARM")
		)
		(zone
			(layer "F.Cu")
			(hatch edge 0.5)
			(connect_pads
				(clearance 0)
			)
			(min_thickness 0.25)
			(keepout
				(tracks allowed)
				(vias allowed)
				(pads allowed)
				(copperpour not_allowed)
				(footprints allowed)
			)
			(placement
				(enabled no)
				(sheetname "")
			)
			(fill
				(thermal_gap 0.5)
				(thermal_bridge_width 0.5)
				(island_removal_mode 0)
			)
			(polygon
				(pts
					(xy 135.99358 120.0662) (xy 135.99359 110.0662) (xy 143.49359 110.0662) (xy 143.49358 120.0662)
				)
			)
		)
	)
	(footprint "Vault:SMTC-TLE-104-01-X-DV"
		(layer "F.Cu")
		(at 225.63905 61.67859 -90)
		(property "Reference" "J13"
			(at -5.408538 1.758945 0)
			(unlocked yes)
			(layer "F.SilkS")
			(effects
				(font
					(size 1.524 1.524)
					(thickness 0.254)
				)
			)
		)
		(property "Value" "GNSS Header"
			(at 6.765575 4.994402 270)
			(unlocked yes)
			(layer "F.SilkS")
			(hide yes)
			(effects
				(font
					(size 1.524 1.524)
					(thickness 0.254)
				)
			)
		)
		(sheetname "GPS_IMU_SENSORS")
		(sheetfile "GPS_IMU_SENSORS.kicad_sch")
		(duplicate_pad_numbers_are_jumpers no)
		(fp_line
			(start -4.06499 2)
			(end -4.06499 -2)
			(stroke
				(width 0.2)
				(type solid)
			)
			(layer "F.SilkS")
		)
		(fp_line
			(start -3.95899 2)
			(end -4.06499 2)
			(stroke
				(width 0.2)
				(type solid)
			)
			(layer "F.SilkS")
		)
		(fp_line
			(start 4.065 2)
			(end 3.959 2)
			(stroke
				(width 0.2)
				(type solid)
			)
			(layer "F.SilkS")
		)
		(fp_line
			(start 4.065 2)
			(end 4.065 -2)
			(stroke
				(width 0.2)
				(type solid)
			)
			(layer "F.SilkS")
		)
		(fp_line
			(start -3.95899 -2)
			(end -4.06499 -2)
			(stroke
				(width 0.2)
				(type solid)
			)
			(layer "F.SilkS")
		)
		(fp_line
			(start 4.065 -2)
			(end 3.959 -2)
			(stroke
				(width 0.2)
				(type solid)
			)
			(layer "F.SilkS")
		)
		(fp_circle
			(center -4.41299 -2.286)
			(end -4.53799 -2.286)
			(stroke
				(width 0.25)
				(type solid)
			)
			(fill no)
			(layer "F.SilkS")
		)
		(pad "1" smd rect
			(at -2.99999 -2.43205 270)
			(size 1.1176 1.6891)
			(layers "F.Cu" "F.Mask" "F.Paste")
			(net "+5.0V")
		)
		(pad "2" smd rect
			(at -2.99999 2.43205 270)
			(size 1.1176 1.6891)
			(layers "F.Cu" "F.Mask" "F.Paste")
			(net "+3.3V")
		)
		(pad "3" smd rect
			(at -0.99999 -2.43205 270)
			(size 1.1176 1.6891)
			(layers "F.Cu" "F.Mask" "F.Paste")
			(net "GPS2_TX")
		)
		(pad "4" smd rect
			(at -0.99999 2.43205 270)
			(size 1.1176 1.6891)
			(layers "F.Cu" "F.Mask" "F.Paste")
			(net "GPS2_RST")
		)
		(pad "5" smd rect
			(at 1 -2.43205 270)
			(size 1.1176 1.6891)
			(layers "F.Cu" "F.Mask" "F.Paste")
			(net "GPS2_RX")
		)
		(pad "6" smd rect
			(at 1 2.43205 270)
			(size 1.1176 1.6891)
			(layers "F.Cu" "F.Mask" "F.Paste")
			(net "GPS2_TP1")
		)
		(pad "7" smd rect
			(at 3 -2.43205 270)
			(size 1.1176 1.6891)
			(layers "F.Cu" "F.Mask" "F.Paste")
			(net "GPS2_TP2")
		)
		(pad "8" smd rect
			(at 3 2.43205 270)
			(size 1.1176 1.6891)
			(layers "F.Cu" "F.Mask" "F.Paste")
			(net "GND")
		)
	)
	(footprint "Capacitors:CAPC2012X14N"
		(layer "F.Cu")
		(at 221.0935 116.1792 -90)
		(property "Reference" "C13"
			(at -1.94991 -0.690055 90)
			(unlocked yes)
			(layer "F.SilkS")
			(effects
				(font
					(size 0.762 0.762)
					(thickness 0.2286)
				)
				(justify left bottom)
			)
		)
		(property "Value" "CAP_0805_10UF_25V"
			(at 6.89119 16.4599 0)
			(unlocked yes)
			(layer "F.SilkS")
			(hide yes)
			(effects
				(font
					(size 1.524 1.524)
					(thickness 0.254)
				)
				(justify left bottom)
			)
		)
		(sheetname "POWER")
		(sheetfile "POWER.kicad_sch")
		(duplicate_pad_numbers_are_jumpers no)
		(fp_line
			(start 0.762 0.9652)
			(end -0.762 0.9652)
			(stroke
				(width 0.1524)
				(type solid)
			)
			(layer "F.SilkS")
		)
		(fp_line
			(start 0.762 -0.9652)
			(end -0.762 -0.9652)
			(stroke
				(width 0.1524)
				(type solid)
			)
			(layer "F.SilkS")
		)
		(pad "1" smd rect
			(at -0.9 0)
			(size 1.45 1.15)
			(layers "F.Cu" "F.Mask" "F.Paste")
			(net "+5.0V")
		)
		(pad "2" smd rect
			(at 0.9 0)
			(size 1.45 1.15)
			(layers "F.Cu" "F.Mask" "F.Paste")
			(net "GND")
		)
	)
	(footprint "Vault:CAPC1608X87X45ML20T05"
		(layer "F.Cu")
		(at 88.1261 79.3286 90)
		(property "Reference" "C61"
			(at -1.25 3.593345 90)
			(unlocked yes)
			(layer "F.SilkS")
			(effects
				(font
					(size 0.762 0.762)
					(thickness 0.2286)
				)
				(justify left bottom)
			)
		)
		(property "Value" "0.1uF"
			(at -3.47599 -0.2921 0)
			(unlocked yes)
			(layer "F.SilkS")
			(hide yes)
			(effects
				(font
					(size 1.524 1.524)
					(thickness 0.254)
				)
				(justify left bottom)
			)
		)
		(sheetname "GPS_IMU_SENSORS")
		(sheetfile "GPS_IMU_SENSORS.kicad_sch")
		(duplicate_pad_numbers_are_jumpers no)
		(pad "1" smd rect
			(at -0.7 0 180)
			(size 1.1 1.05)
			(layers "F.Cu" "F.Mask" "F.Paste")
			(net "GND")
		)
		(pad "2" smd rect
			(at 0.7 0 180)
			(size 1.1 1.05)
			(layers "F.Cu" "F.Mask" "F.Paste")
			(net "+5.0V")
		)
	)
	(footprint "Resistors:RESC2012X50N"
		(layer "F.Cu")
		(at 199.31136 143.47763)
		(property "Reference" "R19"
			(at -1.28526 -1.268085 0)
			(unlocked yes)
			(layer "F.SilkS")
			(effects
				(font
					(size 0.762 0.762)
					(thickness 0.2286)
				)
				(justify left bottom)
			)
		)
		(property "Value" "CRCW080533R0FKEA"
			(at -3.0249 -6.33581 0)
			(unlocked yes)
			(layer "F.SilkS")
			(hide yes)
			(effects
				(font
					(size 1.524 1.524)
					(thickness 0.254)
				)
				(justify left bottom)
			)
		)
		(sheetname "PCIe_JTAG")
		(sheetfile "PCIe_JTAG.kicad_sch")
		(duplicate_pad_numbers_are_jumpers no)
		(fp_line
			(start 0 0.762)
			(end 0 -0.762)
			(stroke
				(width 0.1524)
				(type solid)
			)
			(layer "F.SilkS")
		)
		(pad "1" smd rect
			(at -1 0 90)
			(size 1.45 0.95)
			(layers "F.Cu" "F.Mask" "F.Paste")
			(net "FPGA_TDO")
		)
		(pad "2" smd rect
			(at 1 0 90)
			(size 1.45 0.95)
			(layers "F.Cu" "F.Mask" "F.Paste")
			(net "NetR19_2")
		)
	)
	(footprint "SamacSys:155124M173200"
		(layer "F.Cu")
		(at 58.4511 128.4162 90)
		(property "Reference" "D17"
			(at -0.4714 1.701931 90)
			(unlocked yes)
			(layer "F.SilkS")
			(effects
				(font
					(size 0.762 0.762)
					(thickness 0.2286)
				)
			)
		)
		(property "Value" "155124M173200"
			(at 7.1725 2.632202 90)
			(unlocked yes)
			(layer "F.SilkS")
			(hide yes)
			(effects
				(font
					(size 1.524 1.524)
					(thickness 0.254)
				)
			)
		)
		(sheetname "USER_IO_STATUS")
		(sheetfile "USER_IO_STATUS.kicad_sch")
		(duplicate_pad_numbers_are_jumpers no)
		(fp_line
			(start -0.8 0.5)
			(end 0.8 0.5)
			(stroke
				(width 0.1)
				(type solid)
			)
			(layer "F.SilkS")
		)
		(fp_arc
			(start -2 -0.1)
			(mid -1.95 -0.05)
			(end -2 0)
			(stroke
				(width 0.1)
				(type solid)
			)
			(layer "F.SilkS")
		)
		(fp_arc
			(start -2 0)
			(mid -2.05 -0.05)
			(end -2 -0.1)
			(stroke
				(width 0.1)
				(type solid)
			)
			(layer "F.SilkS")
		)
		(pad "1" smd rect
			(at -1.4 0 180)
			(size 0.9 0.6)
			(layers "F.Cu" "F.Mask" "F.Paste")
			(net "+3.3V")
		)
		(pad "2" smd rect
			(at -0.45 -0.325 90)
			(size 0.6 0.55)
			(layers "F.Cu" "F.Mask" "F.Paste")
			(net "NetD17_2")
		)
		(pad "3" smd rect
			(at 0.45 -0.325 90)
			(size 0.6 0.55)
			(layers "F.Cu" "F.Mask" "F.Paste")
			(net "NetD17_3")
		)
		(pad "4" smd rect
			(at 1.4 0 180)
			(size 0.9 0.6)
			(layers "F.Cu" "F.Mask" "F.Paste")
			(net "NetD17_4")
		)
	)
	(footprint "SamacSys:155124M173200"
		(layer "F.Cu")
		(at 58.4511 114.8162 90)
		(property "Reference" "D16"
			(at -0.5714 1.701931 90)
			(unlocked yes)
			(layer "F.SilkS")
			(effects
				(font
					(size 0.762 0.762)
					(thickness 0.2286)
				)
			)
		)
		(property "Value" "155124M173200"
			(at 7.1725 2.632202 90)
			(unlocked yes)
			(layer "F.SilkS")
			(hide yes)
			(effects
				(font
					(size 1.524 1.524)
					(thickness 0.254)
				)
			)
		)
		(sheetname "USER_IO_STATUS")
		(sheetfile "USER_IO_STATUS.kicad_sch")
		(duplicate_pad_numbers_are_jumpers no)
		(fp_line
			(start -0.8 0.5)
			(end 0.8 0.5)
			(stroke
				(width 0.1)
				(type solid)
			)
			(layer "F.SilkS")
		)
		(fp_arc
			(start -2 -0.1)
			(mid -1.95 -0.05)
			(end -2 0)
			(stroke
				(width 0.1)
				(type solid)
			)
			(layer "F.SilkS")
		)
		(fp_arc
			(start -2 0)
			(mid -2.05 -0.05)
			(end -2 -0.1)
			(stroke
				(width 0.1)
				(type solid)
			)
			(layer "F.SilkS")
		)
		(pad "1" smd rect
			(at -1.4 0 180)
			(size 0.9 0.6)
			(layers "F.Cu" "F.Mask" "F.Paste")
			(net "+3.3V")
		)
		(pad "2" smd rect
			(at -0.45 -0.325 90)
			(size 0.6 0.55)
			(layers "F.Cu" "F.Mask" "F.Paste")
			(net "NetD16_2")
		)
		(pad "3" smd rect
			(at 0.45 -0.325 90)
			(size 0.6 0.55)
			(layers "F.Cu" "F.Mask" "F.Paste")
			(net "NetD16_3")
		)
		(pad "4" smd rect
			(at 1.4 0 180)
			(size 0.9 0.6)
			(layers "F.Cu" "F.Mask" "F.Paste")
			(net "NetD16_4")
		)
	)
)
